(kicad_pcb
	(version 20260206)
	(generator "pcbnew")
	(generator_version "10.0")
	(general
		(thickness 1.6)
		(legacy_teardrops no)
	)
	(paper "A4")
	(title_block
		(title "fcb — Lightning_FCB_BRD.brd")
		(comment 1 "Lightning (Wiwynn / Facebook NVMe JBOF) / footprints 53-59 of 495")
	)
	(layers
		(0 "F.Cu" signal "TOP")
		(4 "In1.Cu" signal "L2GND")
		(6 "In2.Cu" signal "L3VCC")
		(2 "B.Cu" signal "BOTTOM")
		(9 "F.Adhes" user "F.Adhesive")
		(11 "B.Adhes" user "B.Adhesive")
		(13 "F.Paste" user "Package Geometry/Pastemask Top")
		(15 "B.Paste" user "Package Geometry/Pastemask Bottom")
		(5 "F.SilkS" user "Ref Des/Silkscreen Top")
		(7 "B.SilkS" user "Ref Des/Silkscreen Bottom")
		(1 "F.Mask" user "Board Geometry/Soldermask Top")
		(3 "B.Mask" user "Board Geometry/Soldermask Bottom")
		(17 "Dwgs.User" user "User.Drawings")
		(19 "Cmts.User" user "User.Comments")
		(21 "Eco1.User" user "User.Eco1")
		(23 "Eco2.User" user "User.Eco2")
		(25 "Edge.Cuts" user "Board Geometry/Outline")
		(27 "Margin" user)
		(31 "F.CrtYd" user "Package Geometry/Place Bound Top")
		(29 "B.CrtYd" user "Package Geometry/Place Bound Bottom")
		(35 "F.Fab" user "Ref Des/Assembly Top")
		(33 "B.Fab" user "Ref Des/Assembly Bottom")
	)
	(footprint ""
		(layer "F.Cu")
		(at 24.003 -248.793)
		(property "Reference" "PR56"
			(at 0 0 0)
			(layer "F.SilkS")
			(hide yes)
			(effects
				(font
					(size 1.27 1.27)
				)
			)
		)
		(property "Value" "22K1R3F-GP"
			(at -0.0254 -2.5146 0)
			(unlocked yes)
			(layer "F.Fab")
			(hide yes)
			(effects
				(font
					(size 1.016 1.016)
					(thickness 0.1524)
				)
			)
		)
		(property "Device Type" "R603H22"
			(at -0.0254 -4.0386 0)
			(unlocked yes)
			(layer "F.Fab")
			(hide yes)
			(effects
				(font
					(size 1.016 1.016)
					(thickness 0.1524)
				)
			)
		)
		(duplicate_pad_numbers_are_jumpers no)
		(fp_line
			(start -0.4826 0)
			(end -0.2032 0)
			(stroke
				(width 0.2032)
				(type default)
			)
			(layer "F.SilkS")
		)
		(fp_line
			(start 0.2032 0)
			(end 0.4826 0)
			(stroke
				(width 0.2032)
				(type default)
			)
			(layer "F.SilkS")
		)
		(fp_rect
			(start -0.5842 1.3335)
			(end 0.5842 -1.3335)
			(stroke
				(width 0)
				(type default)
			)
			(fill no)
			(layer "F.CrtYd")
		)
		(fp_rect
			(start -0.5842 1.3335)
			(end 0.5842 -1.3335)
			(stroke
				(width 0)
				(type default)
			)
			(fill no)
			(layer "F.Fab")
		)
		(pad "1" smd custom
			(at 0 -0.762)
			(size 0.2159 0.2159)
			(layers "F.Cu" "F.Mask" "F.Paste")
			(net "P3V3_FB")
			(options
				(clearance outline)
				(anchor circle)
			)
			(primitives
				(gr_poly
					(pts
						(arc
							(start -0.3302 -0.4318)
							(mid -0.402042 -0.402042)
							(end -0.4318 -0.3302)
						)
						(arc
							(start -0.4318 0.3302)
							(mid -0.402042 0.402042)
							(end -0.3302 0.4318)
						)
						(arc
							(start 0.3302 0.4318)
							(mid 0.402042 0.402042)
							(end 0.4318 0.3302)
						)
						(arc
							(start 0.4318 -0.3302)
							(mid 0.402042 -0.402042)
							(end 0.3302 -0.4318)
						)
					)
					(width 0)
					(fill yes)
				)
			)
		)
		(pad "2" smd custom
			(at 0 0.762)
			(size 0.2159 0.2159)
			(layers "F.Cu" "F.Mask" "F.Paste")
			(net "GND")
			(options
				(clearance outline)
				(anchor circle)
			)
			(primitives
				(gr_poly
					(pts
						(arc
							(start -0.3302 -0.4318)
							(mid -0.402042 -0.402042)
							(end -0.4318 -0.3302)
						)
						(arc
							(start -0.4318 0.3302)
							(mid -0.402042 0.402042)
							(end -0.3302 0.4318)
						)
						(arc
							(start 0.3302 0.4318)
							(mid 0.402042 0.402042)
							(end 0.4318 0.3302)
						)
						(arc
							(start 0.4318 -0.3302)
							(mid 0.402042 -0.402042)
							(end 0.3302 -0.4318)
						)
					)
					(width 0)
					(fill yes)
				)
			)
		)
	)
	(footprint ""
		(layer "F.Cu")
		(at 13.2588 -61.3918)
		(property "Reference" "C31"
			(at 0 0 0)
			(layer "F.SilkS")
			(hide yes)
			(effects
				(font
					(size 1.27 1.27)
				)
			)
		)
		(property "Value" "SCD1U50V3KX-GP"
			(at 0 -2.8194 0)
			(unlocked yes)
			(layer "F.Fab")
			(hide yes)
			(effects
				(font
					(size 1.016 1.016)
					(thickness 0.1524)
				)
			)
		)
		(property "Device Type" "C603H36"
			(at 0 -4.3434 0)
			(unlocked yes)
			(layer "F.Fab")
			(hide yes)
			(effects
				(font
					(size 1.016 1.016)
					(thickness 0.1524)
				)
			)
		)
		(duplicate_pad_numbers_are_jumpers no)
		(fp_line
			(start 0.508 0)
			(end -0.508 0)
			(stroke
				(width 0.2032)
				(type default)
			)
			(layer "F.SilkS")
		)
		(fp_rect
			(start -0.5842 1.3335)
			(end 0.5842 -1.3335)
			(stroke
				(width 0)
				(type default)
			)
			(fill no)
			(layer "F.CrtYd")
		)
		(fp_rect
			(start -0.5842 1.3335)
			(end 0.5842 -1.3335)
			(stroke
				(width 0)
				(type default)
			)
			(fill no)
			(layer "F.Fab")
		)
		(pad "1" smd custom
			(at 0 -0.762)
			(size 0.2159 0.2159)
			(layers "F.Cu" "F.Mask" "F.Paste")
			(net "P12V")
			(options
				(clearance outline)
				(anchor circle)
			)
			(primitives
				(gr_poly
					(pts
						(arc
							(start -0.3302 -0.4318)
							(mid -0.402042 -0.402042)
							(end -0.4318 -0.3302)
						)
						(arc
							(start -0.4318 0.3302)
							(mid -0.402042 0.402042)
							(end -0.3302 0.4318)
						)
						(arc
							(start 0.3302 0.4318)
							(mid 0.402042 0.402042)
							(end 0.4318 0.3302)
						)
						(arc
							(start 0.4318 -0.3302)
							(mid 0.402042 -0.402042)
							(end 0.3302 -0.4318)
						)
					)
					(width 0)
					(fill yes)
				)
			)
		)
		(pad "2" smd custom
			(at 0 0.762)
			(size 0.2159 0.2159)
			(layers "F.Cu" "F.Mask" "F.Paste")
			(net "GND")
			(options
				(clearance outline)
				(anchor circle)
			)
			(primitives
				(gr_poly
					(pts
						(arc
							(start -0.3302 -0.4318)
							(mid -0.402042 -0.402042)
							(end -0.4318 -0.3302)
						)
						(arc
							(start -0.4318 0.3302)
							(mid -0.402042 0.402042)
							(end -0.3302 0.4318)
						)
						(arc
							(start 0.3302 0.4318)
							(mid 0.402042 0.402042)
							(end 0.4318 0.3302)
						)
						(arc
							(start 0.4318 -0.3302)
							(mid 0.402042 -0.402042)
							(end 0.3302 -0.4318)
						)
					)
					(width 0)
					(fill yes)
				)
			)
		)
	)
	(footprint ""
		(layer "F.Cu")
		(at 23.48611 -154.602434)
		(property "Reference" "R4"
			(at 0 0 0)
			(layer "F.SilkS")
			(hide yes)
			(effects
				(font
					(size 1.27 1.27)
				)
			)
		)
		(property "Value" "0R2J-2-GP"
			(at 0.064008 -3.993896 0)
			(unlocked yes)
			(layer "F.Fab")
			(hide yes)
			(effects
				(font
					(size 1.016 1.016)
					(thickness 0.1524)
				)
			)
		)
		(property "Device Type" "R402H16"
			(at 0.064008 -5.517896 0)
			(unlocked yes)
			(layer "F.Fab")
			(hide yes)
			(effects
				(font
					(size 1.016 1.016)
					(thickness 0.1524)
				)
			)
		)
		(duplicate_pad_numbers_are_jumpers no)
		(fp_line
			(start -0.508 -0.9398)
			(end -0.508 0.9398)
			(stroke
				(width 0.1524)
				(type default)
			)
			(layer "F.SilkS")
		)
		(fp_line
			(start 0.508 -0.9398)
			(end -0.508 -0.9398)
			(stroke
				(width 0.1524)
				(type default)
			)
			(layer "F.SilkS")
		)
		(fp_rect
			(start -0.508 0.9398)
			(end 0.508 -0.9398)
			(stroke
				(width 0)
				(type default)
			)
			(fill no)
			(layer "F.CrtYd")
		)
		(fp_rect
			(start -0.508 0.9398)
			(end 0.508 -0.9398)
			(stroke
				(width 0)
				(type default)
			)
			(fill no)
			(layer "F.Fab")
		)
		(pad "1" smd custom
			(at 0 -0.4445)
			(size 0.1397 0.1397)
			(layers "F.Cu" "F.Mask" "F.Paste")
			(net "NCT7904_TMPALM")
			(options
				(clearance outline)
				(anchor circle)
			)
			(primitives
				(gr_poly
					(pts
						(arc
							(start -0.1778 -0.2794)
							(mid -0.249642 -0.249642)
							(end -0.2794 -0.1778)
						)
						(arc
							(start -0.2794 0.1778)
							(mid -0.249642 0.249642)
							(end -0.1778 0.2794)
						)
						(arc
							(start 0.1778 0.2794)
							(mid 0.249642 0.249642)
							(end 0.2794 0.1778)
						)
						(arc
							(start 0.2794 -0.1778)
							(mid 0.249642 -0.249642)
							(end 0.1778 -0.2794)
						)
					)
					(width 0)
					(fill yes)
				)
			)
		)
		(pad "2" smd custom
			(at 0 0.4445)
			(size 0.1397 0.1397)
			(layers "F.Cu" "F.Mask" "F.Paste")
			(net "TEMP_ALM#")
			(options
				(clearance outline)
				(anchor circle)
			)
			(primitives
				(gr_poly
					(pts
						(arc
							(start -0.1778 -0.2794)
							(mid -0.249642 -0.249642)
							(end -0.2794 -0.1778)
						)
						(arc
							(start -0.2794 0.1778)
							(mid -0.249642 0.249642)
							(end -0.1778 0.2794)
						)
						(arc
							(start 0.1778 0.2794)
							(mid 0.249642 0.249642)
							(end 0.2794 0.1778)
						)
						(arc
							(start 0.2794 -0.1778)
							(mid 0.249642 -0.249642)
							(end 0.1778 -0.2794)
						)
					)
					(width 0)
					(fill yes)
				)
			)
		)
	)
	(footprint ""
		(layer "F.Cu")
		(at 32.766 -381 180)
		(property "Reference" "PR22"
			(at 0 0 180)
			(layer "F.SilkS")
			(hide yes)
			(effects
				(font
					(size 1.27 1.27)
				)
			)
		)
		(property "Value" "10R2F-L-GP"
			(at 0.064008 -3.993896 180)
			(unlocked yes)
			(layer "F.Fab")
			(hide yes)
			(effects
				(font
					(size 1.016 1.016)
					(thickness 0.1524)
				)
			)
		)
		(property "Device Type" "R402H14"
			(at 0.064008 -5.517896 180)
			(unlocked yes)
			(layer "F.Fab")
			(hide yes)
			(effects
				(font
					(size 1.016 1.016)
					(thickness 0.1524)
				)
			)
		)
		(duplicate_pad_numbers_are_jumpers no)
		(fp_line
			(start 0.508 -0.9398)
			(end -0.508 -0.9398)
			(stroke
				(width 0.1524)
				(type default)
			)
			(layer "F.SilkS")
		)
		(fp_line
			(start -0.508 -0.9398)
			(end -0.508 0.9398)
			(stroke
				(width 0.1524)
				(type default)
			)
			(layer "F.SilkS")
		)
		(fp_rect
			(start -0.508 0.9398)
			(end 0.508 -0.9398)
			(stroke
				(width 0)
				(type default)
			)
			(fill no)
			(layer "F.CrtYd")
		)
		(fp_rect
			(start -0.508 0.9398)
			(end 0.508 -0.9398)
			(stroke
				(width 0)
				(type default)
			)
			(fill no)
			(layer "F.Fab")
		)
		(pad "1" smd custom
			(at 0 -0.4445 180)
			(size 0.1397 0.1397)
			(layers "F.Cu" "F.Mask" "F.Paste")
			(net "ADM1276_SENSE-")
			(options
				(clearance outline)
				(anchor circle)
			)
			(primitives
				(gr_poly
					(pts
						(arc
							(start -0.1778 -0.2794)
							(mid -0.249642 -0.249642)
							(end -0.2794 -0.1778)
						)
						(arc
							(start -0.2794 0.1778)
							(mid -0.249642 0.249642)
							(end -0.1778 0.2794)
						)
						(arc
							(start 0.1778 0.2794)
							(mid 0.249642 0.249642)
							(end 0.2794 0.1778)
						)
						(arc
							(start 0.2794 -0.1778)
							(mid 0.249642 -0.249642)
							(end 0.1778 -0.2794)
						)
					)
					(width 0)
					(fill yes)
				)
			)
		)
		(pad "2" smd custom
			(at 0 0.4445 180)
			(size 0.1397 0.1397)
			(layers "F.Cu" "F.Mask" "F.Paste")
			(net "SENSE-_R2")
			(options
				(clearance outline)
				(anchor circle)
			)
			(primitives
				(gr_poly
					(pts
						(arc
							(start -0.1778 -0.2794)
							(mid -0.249642 -0.249642)
							(end -0.2794 -0.1778)
						)
						(arc
							(start -0.2794 0.1778)
							(mid -0.249642 0.249642)
							(end -0.1778 0.2794)
						)
						(arc
							(start 0.1778 0.2794)
							(mid 0.249642 0.249642)
							(end 0.2794 0.1778)
						)
						(arc
							(start 0.2794 -0.1778)
							(mid 0.249642 -0.249642)
							(end 0.1778 -0.2794)
						)
					)
					(width 0)
					(fill yes)
				)
			)
		)
	)
	(footprint ""
		(layer "F.Cu")
		(at 28.702 -381 180)
		(property "Reference" "PR18"
			(at 0 0 180)
			(layer "F.SilkS")
			(hide yes)
			(effects
				(font
					(size 1.27 1.27)
				)
			)
		)
		(property "Value" "10R2F-L-GP"
			(at 0.064008 -3.993896 180)
			(unlocked yes)
			(layer "F.Fab")
			(hide yes)
			(effects
				(font
					(size 1.016 1.016)
					(thickness 0.1524)
				)
			)
		)
		(property "Device Type" "R402H14"
			(at 0.064008 -5.517896 180)
			(unlocked yes)
			(layer "F.Fab")
			(hide yes)
			(effects
				(font
					(size 1.016 1.016)
					(thickness 0.1524)
				)
			)
		)
		(duplicate_pad_numbers_are_jumpers no)
		(fp_line
			(start 0.508 -0.9398)
			(end -0.508 -0.9398)
			(stroke
				(width 0.1524)
				(type default)
			)
			(layer "F.SilkS")
		)
		(fp_line
			(start -0.508 -0.9398)
			(end -0.508 0.9398)
			(stroke
				(width 0.1524)
				(type default)
			)
			(layer "F.SilkS")
		)
		(fp_rect
			(start -0.508 0.9398)
			(end 0.508 -0.9398)
			(stroke
				(width 0)
				(type default)
			)
			(fill no)
			(layer "F.CrtYd")
		)
		(fp_rect
			(start -0.508 0.9398)
			(end 0.508 -0.9398)
			(stroke
				(width 0)
				(type default)
			)
			(fill no)
			(layer "F.Fab")
		)
		(pad "1" smd custom
			(at 0 -0.4445 180)
			(size 0.1397 0.1397)
			(layers "F.Cu" "F.Mask" "F.Paste")
			(net "ADM1276_SENSE+")
			(options
				(clearance outline)
				(anchor circle)
			)
			(primitives
				(gr_poly
					(pts
						(arc
							(start -0.1778 -0.2794)
							(mid -0.249642 -0.249642)
							(end -0.2794 -0.1778)
						)
						(arc
							(start -0.2794 0.1778)
							(mid -0.249642 0.249642)
							(end -0.1778 0.2794)
						)
						(arc
							(start 0.1778 0.2794)
							(mid 0.249642 0.249642)
							(end 0.2794 0.1778)
						)
						(arc
							(start 0.2794 -0.1778)
							(mid 0.249642 -0.249642)
							(end 0.1778 -0.2794)
						)
					)
					(width 0)
					(fill yes)
				)
			)
		)
		(pad "2" smd custom
			(at 0 0.4445 180)
			(size 0.1397 0.1397)
			(layers "F.Cu" "F.Mask" "F.Paste")
			(net "SENSE+_R3")
			(options
				(clearance outline)
				(anchor circle)
			)
			(primitives
				(gr_poly
					(pts
						(arc
							(start -0.1778 -0.2794)
							(mid -0.249642 -0.249642)
							(end -0.2794 -0.1778)
						)
						(arc
							(start -0.2794 0.1778)
							(mid -0.249642 0.249642)
							(end -0.1778 0.2794)
						)
						(arc
							(start 0.1778 0.2794)
							(mid 0.249642 0.249642)
							(end 0.2794 0.1778)
						)
						(arc
							(start 0.2794 -0.1778)
							(mid 0.249642 -0.249642)
							(end 0.1778 -0.2794)
						)
					)
					(width 0)
					(fill yes)
				)
			)
		)
	)
	(footprint ""
		(layer "F.Cu")
		(at 20.381976 -176.43729 -90)
		(property "Reference" "R24"
			(at 0 0 270)
			(layer "F.SilkS")
			(hide yes)
			(effects
				(font
					(size 1.27 1.27)
				)
			)
		)
		(property "Value" "4K7R2F-GP"
			(at 0.064008 -3.993896 270)
			(unlocked yes)
			(layer "F.Fab")
			(hide yes)
			(effects
				(font
					(size 1.016 1.016)
					(thickness 0.1524)
				)
			)
		)
		(property "Device Type" "R402H16"
			(at 0.064008 -5.517896 270)
			(unlocked yes)
			(layer "F.Fab")
			(hide yes)
			(effects
				(font
					(size 1.016 1.016)
					(thickness 0.1524)
				)
			)
		)
		(duplicate_pad_numbers_are_jumpers no)
		(fp_line
			(start -0.508 -0.9398)
			(end -0.508 0.9398)
			(stroke
				(width 0.1524)
				(type default)
			)
			(layer "F.SilkS")
		)
		(fp_line
			(start 0.508 -0.9398)
			(end -0.508 -0.9398)
			(stroke
				(width 0.1524)
				(type default)
			)
			(layer "F.SilkS")
		)
		(fp_rect
			(start -0.508 0.9398)
			(end 0.508 -0.9398)
			(stroke
				(width 0)
				(type default)
			)
			(fill no)
			(layer "F.CrtYd")
		)
		(fp_rect
			(start -0.508 0.9398)
			(end 0.508 -0.9398)
			(stroke
				(width 0)
				(type default)
			)
			(fill no)
			(layer "F.Fab")
		)
		(pad "1" smd custom
			(at 0 -0.4445 270)
			(size 0.1397 0.1397)
			(layers "F.Cu" "F.Mask" "F.Paste")
			(net "NCT7368S_SEL")
			(options
				(clearance outline)
				(anchor circle)
			)
			(primitives
				(gr_poly
					(pts
						(arc
							(start -0.1778 -0.2794)
							(mid -0.249642 -0.249642)
							(end -0.2794 -0.1778)
						)
						(arc
							(start -0.2794 0.1778)
							(mid -0.249642 0.249642)
							(end -0.1778 0.2794)
						)
						(arc
							(start 0.1778 0.2794)
							(mid 0.249642 0.249642)
							(end 0.2794 0.1778)
						)
						(arc
							(start 0.2794 -0.1778)
							(mid 0.249642 -0.249642)
							(end 0.1778 -0.2794)
						)
					)
					(width 0)
					(fill yes)
				)
			)
		)
		(pad "2" smd custom
			(at 0 0.4445 270)
			(size 0.1397 0.1397)
			(layers "F.Cu" "F.Mask" "F.Paste")
			(net "GND")
			(options
				(clearance outline)
				(anchor circle)
			)
			(primitives
				(gr_poly
					(pts
						(arc
							(start -0.1778 -0.2794)
							(mid -0.249642 -0.249642)
							(end -0.2794 -0.1778)
						)
						(arc
							(start -0.2794 0.1778)
							(mid -0.249642 0.249642)
							(end -0.1778 0.2794)
						)
						(arc
							(start 0.1778 0.2794)
							(mid 0.249642 0.249642)
							(end 0.2794 0.1778)
						)
						(arc
							(start 0.2794 -0.1778)
							(mid 0.249642 -0.249642)
							(end 0.1778 -0.2794)
						)
					)
					(width 0)
					(fill yes)
				)
			)
		)
	)
	(footprint ""
		(layer "F.Cu")
		(at 34.925 -366.268)
		(property "Reference" "PR38"
			(at 0 0 0)
			(layer "F.SilkS")
			(hide yes)
			(effects
				(font
					(size 1.27 1.27)
				)
			)
		)
		(property "Value" "1KR2F-3-GP"
			(at 0.064008 -3.993896 0)
			(unlocked yes)
			(layer "F.Fab")
			(hide yes)
			(effects
				(font
					(size 1.016 1.016)
					(thickness 0.1524)
				)
			)
		)
		(property "Device Type" "R402H16"
			(at 0.064008 -5.517896 0)
			(unlocked yes)
			(layer "F.Fab")
			(hide yes)
			(effects
				(font
					(size 1.016 1.016)
					(thickness 0.1524)
				)
			)
		)
		(duplicate_pad_numbers_are_jumpers no)
		(fp_line
			(start -0.508 -0.9398)
			(end -0.508 0.9398)
			(stroke
				(width 0.1524)
				(type default)
			)
			(layer "F.SilkS")
		)
		(fp_line
			(start 0.508 -0.9398)
			(end -0.508 -0.9398)
			(stroke
				(width 0.1524)
				(type default)
			)
			(layer "F.SilkS")
		)
		(fp_rect
			(start -0.508 0.9398)
			(end 0.508 -0.9398)
			(stroke
				(width 0)
				(type default)
			)
			(fill no)
			(layer "F.CrtYd")
		)
		(fp_rect
			(start -0.508 0.9398)
			(end 0.508 -0.9398)
			(stroke
				(width 0)
				(type default)
			)
			(fill no)
			(layer "F.Fab")
		)
		(pad "1" smd custom
			(at 0 -0.4445)
			(size 0.1397 0.1397)
			(layers "F.Cu" "F.Mask" "F.Paste")
			(net "ADM1276_EN_NET")
			(options
				(clearance outline)
				(anchor circle)
			)
			(primitives
				(gr_poly
					(pts
						(arc
							(start -0.1778 -0.2794)
							(mid -0.249642 -0.249642)
							(end -0.2794 -0.1778)
						)
						(arc
							(start -0.2794 0.1778)
							(mid -0.249642 0.249642)
							(end -0.1778 0.2794)
						)
						(arc
							(start 0.1778 0.2794)
							(mid 0.249642 0.249642)
							(end 0.2794 0.1778)
						)
						(arc
							(start 0.2794 -0.1778)
							(mid 0.249642 -0.249642)
							(end 0.1778 -0.2794)
						)
					)
					(width 0)
					(fill yes)
				)
			)
		)
		(pad "2" smd custom
			(at 0 0.4445)
			(size 0.1397 0.1397)
			(layers "F.Cu" "F.Mask" "F.Paste")
			(net "ADM1276_EN")
			(options
				(clearance outline)
				(anchor circle)
			)
			(primitives
				(gr_poly
					(pts
						(arc
							(start -0.1778 -0.2794)
							(mid -0.249642 -0.249642)
							(end -0.2794 -0.1778)
						)
						(arc
							(start -0.2794 0.1778)
							(mid -0.249642 0.249642)
							(end -0.1778 0.2794)
						)
						(arc
							(start 0.1778 0.2794)
							(mid 0.249642 0.249642)
							(end 0.2794 0.1778)
						)
						(arc
							(start 0.2794 -0.1778)
							(mid 0.249642 -0.249642)
							(end 0.1778 -0.2794)
						)
					)
					(width 0)
					(fill yes)
				)
			)
		)
	)
)
